# S9S_MB_2U (Grand Teton) — schematic netlist excerpt (pin names and nets, part order shuffled) for the footprints in the layout excerpt that follows; sources: Cadence DE-HDL packaged netlist, KiCad conversion of 03242023_DA0F0TMBIJ0_F0T_Motherboard_J_brd_V01_OCP.brd

PC522_P1_5  Q_CAP  22UF 4V 20% X6S  pkg C0805  page 287 : A = PVCCIN_CPU1 ; B = GND
R3505  Q_RES  33.2 1% CHIP  pkg 0402LF  page 213 : A = GPU_FPGA_EROT_FATALERR_ISO_N ; B = GPU_FPGA_EROT_FATALERR_ISO_R_N

(kicad_pcb
	(version 20260206)
	(generator "pcbnew")
	(generator_version "10.0")
	(general
		(thickness 1.6)
		(legacy_teardrops no)
	)
	(paper "A4")
	(title_block
		(title "03242023_DA0F0TMBIJ0_F0T_Motherboard_J_brd_V01_OCP.brd")
		(comment 1 "Grand Teton / footprints 5465-5466 of 6105")
	)
	(layers
		(0 "F.Cu" signal "TOP")
		(4 "In1.Cu" signal "GND")
		(6 "In2.Cu" signal "IN1")
		(8 "In3.Cu" signal "GND1")
		(10 "In4.Cu" signal "IN2")
		(12 "In5.Cu" signal "GND2")
		(14 "In6.Cu" signal "IN3")
		(16 "In7.Cu" signal "GND3")
		(18 "In8.Cu" signal "VCC")
		(20 "In9.Cu" signal "VCC1")
		(22 "In10.Cu" signal "GND4")
		(24 "In11.Cu" signal "IN4")
		(26 "In12.Cu" signal "GND5")
		(28 "In13.Cu" signal "IN5")
		(30 "In14.Cu" signal "GND6")
		(32 "In15.Cu" signal "IN6")
		(34 "In16.Cu" signal "GND7")
		(2 "B.Cu" signal "BOTTOM")
		(9 "F.Adhes" user "F.Adhesive")
		(11 "B.Adhes" user "B.Adhesive")
		(13 "F.Paste" user "Package Geometry/Pastemask Top")
		(15 "B.Paste" user "Package Geometry/Pastemask Bottom")
		(5 "F.SilkS" user "Ref Des/Silkscreen Top")
		(7 "B.SilkS" user "Ref Des/Silkscreen Bottom")
		(1 "F.Mask" user "Board Geometry/Soldermask Top")
		(3 "B.Mask" user "Board Geometry/Soldermask Bottom")
		(17 "Dwgs.User" user "User.Drawings")
		(19 "Cmts.User" user "User.Comments")
		(21 "Eco1.User" user "User.Eco1")
		(23 "Eco2.User" user "User.Eco2")
		(25 "Edge.Cuts" user "Board Geometry/Outline")
		(27 "Margin" user)
		(31 "F.CrtYd" user "Package Geometry/Place Bound Top")
		(29 "B.CrtYd" user "Package Geometry/Place Bound Bottom")
		(35 "F.Fab" user "Ref Des/Assembly Top")
		(33 "B.Fab" user "Ref Des/Assembly Bottom")
	)
	(footprint ""
		(layer "B.Cu")
		(at 164.64788 -115.026948 180)
		(property "Reference" "R3505"
			(at 0 0 0)
			(layer "B.SilkS")
			(hide yes)
			(effects
				(font
					(size 1.27 1.27)
				)
				(justify mirror)
			)
		)
		(property "Value" ""
			(at 0 0 0)
			(layer "B.Fab")
			(effects
				(font
					(size 1.27 1.27)
				)
				(justify mirror)
			)
		)
		(duplicate_pad_numbers_are_jumpers no)
		(fp_line
			(start 0.7874 0.4064)
			(end 0.7874 -0.4064)
			(stroke
				(width 0.1524)
				(type default)
			)
			(layer "B.SilkS")
		)
		(fp_line
			(start 0.7874 -0.4064)
			(end -0.7874 -0.4064)
			(stroke
				(width 0.1524)
				(type default)
			)
			(layer "B.SilkS")
		)
		(fp_line
			(start -0.7874 0.4064)
			(end 0.7874 0.4064)
			(stroke
				(width 0.1524)
				(type default)
			)
			(layer "B.SilkS")
		)
		(fp_line
			(start -0.7874 -0.4064)
			(end -0.7874 0.4064)
			(stroke
				(width 0.1524)
				(type default)
			)
			(layer "B.SilkS")
		)
		(fp_line
			(start 0.67945 0.3048)
			(end 0.67945 -0.305054)
			(stroke
				(width 0.1)
				(type default)
			)
			(layer "B.Fab")
		)
		(fp_line
			(start 0.67945 -0.305054)
			(end 0.12065 -0.305054)
			(stroke
				(width 0.1)
				(type default)
			)
			(layer "B.Fab")
		)
		(fp_line
			(start 0.12065 0.3048)
			(end 0.67945 0.3048)
			(stroke
				(width 0.1)
				(type default)
			)
			(layer "B.Fab")
		)
		(fp_line
			(start 0.12065 0.2794)
			(end 0.12065 0.3048)
			(stroke
				(width 0.1)
				(type default)
			)
			(layer "B.Fab")
		)
		(fp_line
			(start 0.12065 -0.2794)
			(end -0.12065 -0.2794)
			(stroke
				(width 0.1)
				(type default)
			)
			(layer "B.Fab")
		)
		(fp_line
			(start 0.12065 -0.305054)
			(end 0.12065 -0.2794)
			(stroke
				(width 0.1)
				(type default)
			)
			(layer "B.Fab")
		)
		(fp_line
			(start -0.120396 0.3048)
			(end -0.120396 0.2794)
			(stroke
				(width 0.1)
				(type default)
			)
			(layer "B.Fab")
		)
		(fp_line
			(start -0.120396 0.2794)
			(end 0.12065 0.2794)
			(stroke
				(width 0.1)
				(type default)
			)
			(layer "B.Fab")
		)
		(fp_line
			(start -0.12065 -0.2794)
			(end -0.12065 -0.3048)
			(stroke
				(width 0.1)
				(type default)
			)
			(layer "B.Fab")
		)
		(fp_line
			(start -0.12065 -0.3048)
			(end -0.67945 -0.3048)
			(stroke
				(width 0.1)
				(type default)
			)
			(layer "B.Fab")
		)
		(fp_line
			(start -0.67945 0.3048)
			(end -0.120396 0.3048)
			(stroke
				(width 0.1)
				(type default)
			)
			(layer "B.Fab")
		)
		(fp_line
			(start -0.67945 -0.3048)
			(end -0.67945 0.3048)
			(stroke
				(width 0.1)
				(type default)
			)
			(layer "B.Fab")
		)
		(pad "1" smd circle
			(at 0.40005 0)
			(size 0 0)
			(layers "B.Cu" "B.Mask" "B.Paste")
			(net "GPU_FPGA_EROT_FATALERR_ISO_N")
		)
		(pad "2" smd circle
			(at -0.40005 0)
			(size 0 0)
			(layers "B.Cu" "B.Mask" "B.Paste")
			(net "GPU_FPGA_EROT_FATALERR_ISO_R_N")
		)
	)
	(footprint ""
		(layer "B.Cu")
		(at 133.069838 -328.298048 -90)
		(property "Reference" "PC522_P1_5"
			(at 0 0 90)
			(layer "B.SilkS")
			(hide yes)
			(effects
				(font
					(size 1.27 1.27)
				)
				(justify mirror)
			)
		)
		(property "Value" ""
			(at 0 0 90)
			(layer "B.Fab")
			(effects
				(font
					(size 1.27 1.27)
				)
				(justify mirror)
			)
		)
		(duplicate_pad_numbers_are_jumpers no)
		(fp_line
			(start -1.524 0.762)
			(end 1.524 0.762)
			(stroke
				(width 0.1524)
				(type default)
			)
			(layer "B.SilkS")
		)
		(fp_line
			(start 1.524 0.762)
			(end 1.524 -0.762)
			(stroke
				(width 0.1524)
				(type default)
			)
			(layer "B.SilkS")
		)
		(fp_line
			(start -1.524 -0.762)
			(end -1.524 0.762)
			(stroke
				(width 0.1524)
				(type default)
			)
			(layer "B.SilkS")
		)
		(fp_line
			(start 1.524 -0.762)
			(end -1.524 -0.762)
			(stroke
				(width 0.1524)
				(type default)
			)
			(layer "B.SilkS")
		)
		(fp_line
			(start -1.1049 0.724916)
			(end -1.1049 -0.724916)
			(stroke
				(width 0.1)
				(type default)
			)
			(layer "B.Fab")
		)
		(fp_line
			(start 1.1049 0.724916)
			(end -1.1049 0.724916)
			(stroke
				(width 0.1)
				(type default)
			)
			(layer "B.Fab")
		)
		(fp_line
			(start -1.1049 -0.724916)
			(end 1.1049 -0.724916)
			(stroke
				(width 0.1)
				(type default)
			)
			(layer "B.Fab")
		)
		(fp_line
			(start 1.1049 -0.724916)
			(end 1.1049 0.724916)
			(stroke
				(width 0.1)
				(type default)
			)
			(layer "B.Fab")
		)
		(pad "1" smd rect
			(at 0.889 0 270)
			(size 1.016 1.27)
			(layers "B.Cu" "B.Mask" "B.Paste")
			(net "PVCCIN_CPU1")
		)
		(pad "2" smd rect
			(at -0.889 0 270)
			(size 1.016 1.27)
			(layers "B.Cu" "B.Mask" "B.Paste")
			(net "GND")
		)
	)
)
